FILE_TYPE = CONNECTIVITY;
{Allegro Design Entry HDL 16.6-p007 (v16-6-112F) 10/10/2012}
"PAGE_NUMBER" = 181;
0"NC";
1"P3E_CPU1_PE3_MP_RXP<7:0>";
2"P3E_CPU1_PE3_MP_RXN<7:0>";
3"P3E_CPU1_PE3_MP_TXP<7:0>";
4"P3E_CPU1_PE3_MP_TXN<7:0>";
5"GND\g";
6"P12V_PSU\g";
7"GND\g";
8"P12V_PSU\g";
9"GND\g";
10"GND\g";
11"P3V3_STBY\g";
12"GND\g";
13"P3V3_STBY\g";
14"GND\g";
15"P3V3_STBY\g";
16"GND\g";
17"GND\g";
18"FAN_PWM_OUT_SYS0_R1";
19"CLK_100M_AIRMAX8_PE1_DN";
20"P3E_CPU1_PE3_MP_TXP<2>";
21"FAN_TACH2_R";
22"FAN_TACH3";
23"P3E_CPU1_PE3_MP_C_TXN<1>";
24"P3E_CPU1_PE3_MP_TXP<4>";
25"P3E_CPU1_PE3_MP_TXN<7>";
26"P3E_CPU1_PE3_MP_TXP<7>";
27"P3E_CPU1_PE3_MP_TXP<6>";
28"P3E_CPU1_PE3_MP_TXN<6>";
29"FM_MATED_IN_N";
30"FM_MATED_IN_D1_N";
31"FM_ENABLE_FAN_POWER";
32"SPA_MID_DBG_RX_R";
33"FAN_TACH1_R";
34"FAN_TACH0_R";
35"CLK_100M_AIRMAX8_PE1_DP";
36"FAN_PWM_OUT_SYS0_R";
37"FM_MATED_IN_N";
38"SP2_BMC_CM_UART_TX_R1";
39"FAN_TACH0";
40"FAN_TACH3_R";
41"FAN_TACH1";
42"SPA_MID_DBG_TX_R";
43"P3E_CPU1_PE3_MP_RXN<2>";
44"SPA_MID_DBG_TX";
45"SPA_MID_DBG_RX";
46"SP2_BMC_CM_UART_RX_R1";
47"FAN_TACH2";
48"P3E_CPU1_PE3_MP_RXP<2>";
49"FM_PS_EN";
50"FM_MB_SLOT_ID2";
51"FM_MB_SLOT_ID1";
52"FM_MB_SLOT_ID0";
53"FM_MATED_IN_N";
54"IRQ_SML1_PMBUS_ALERT_R_N";
55"SMB_BMC_PMBUS_STBY_LVC3_SCL";
56"SMB_BMC_PMBUS_STBY_LVC3_SDA";
57"FM_MP_PS_FAIL_N";
58"FM_MP_PS_REDUNDANT_LOST_N";
59"P3E_CPU1_PE3_MP_TXN<3>";
60"P3E_CPU1_PE3_MP_TXP<5>";
61"P3E_CPU1_PE3_MP_TXN<4>";
62"P3E_CPU1_PE3_MP_TXN<0>";
63"P3E_CPU1_PE3_MP_TXN<2>";
64"P3E_CPU1_PE3_MP_TXN<1>";
65"P3E_CPU1_PE3_MP_TXP<1>";
66"P3E_CPU1_PE3_MP_TXP<3>";
67"P3E_CPU1_PE3_MP_TXN<5>";
68"P3E_CPU1_PE3_MP_TXP<0>";
69"FM_P12V_HOTSWAP0_EN";
70"FM_CTNR_PS_ON";
71"FM_CTNR_PS_ON_R";
72"P3E_CPU1_PE3_MP_C_TXP<7>";
73"P3E_CPU1_PE3_MP_C_TXN<7>";
74"P3E_CPU1_PE3_MP_C_TXN<3>";
75"P3E_CPU1_PE3_MP_C_TXN<4>";
76"P3E_CPU1_PE3_MP_C_TXP<4>";
77"P3E_CPU1_PE3_MP_C_TXP<0>";
78"P3E_CPU1_PE3_MP_C_TXP<1>";
79"P3E_CPU1_PE3_MP_C_TXN<2>";
80"P3E_CPU1_PE3_MP_C_TXN<0>";
81"P3E_CPU1_PE3_MP_C_TXN<6>";
82"P3E_CPU1_PE3_MP_C_TXP<2>";
83"P3E_CPU1_PE3_MP_C_TXP<6>";
84"P3E_CPU1_PE3_MP_C_TXP<3>";
85"P3E_CPU1_PE3_MP_C_TXN<5>";
86"P3E_CPU1_PE3_MP_C_TXP<5>";
87"NIC_MDI_MNG_TX_DP";
88"NIC_MDI_MNG_TX_DN";
89"NIC_MDI_MNG_RX_DP";
90"NIC_MDI_MNG_RX_DN";
91"RST_PCIE_MIDPLANE_N";
92"IRQ_SML1_PMBUS_ALERT_R_N";
93"SMB_BMC_PMBUS_STBY_LVC3_SCL";
94"SMB_BMC_PMBUS_STBY_LVC3_SDA";
95"PWRGD_P12V_HSC_DLY";
96"FM_MB_SLOT_ID0";
97"FM_MB_SLOT_ID1";
98"FM_MB_SLOT_ID2";
99"P3E_CPU1_PE3_MP_RXP<3>";
100"P3E_CPU1_PE3_MP_RXP<1>";
101"P3E_CPU1_PE3_MP_RXP<0>";
102"P3E_CPU1_PE3_MP_RXN<0>";
103"P3E_CPU1_PE3_MP_RXN<1>";
104"P3E_CPU1_PE3_MP_RXN<3>";
105"P3E_CPU1_PE3_MP_RXN<7>";
106"P3E_CPU1_PE3_MP_RXN<4>";
107"P3E_CPU1_PE3_MP_RXP<7>";
108"P3E_CPU1_PE3_MP_RXP<6>";
109"P3E_CPU1_PE3_MP_RXN<6>";
110"P3E_CPU1_PE3_MP_RXP<5>";
111"P3E_CPU1_PE3_MP_RXN<5>";
112"P3E_CPU1_PE3_MP_RXP<4>";
113"FM_MATED_IN_D2_N";
%"CONN76_H22707001"
"1","(-625,3800)","0","mstr_conn","I111";
;
CDS_SEC"1"
CDS_LIB"mstr_conn"
CDS_LOCATION"J1F1"
PACK_TYPE"THMT1"
SEC_TYPE"THMT1"
SEC"1"
ROOM"IO_SLOT"
BOM_COST"IO_SLOT"
LOCATION"J1F1"
MATERIAL"CONN"
PART_NUMBER"H22707-001";
"GNDF5"
$PN"F5"96;
"IOG5"
$PN"G5"97;
"IOH5"
$PN"H5"98;
"GNDI5"
$PN"I5"91;
"GNDJ4"
$PN"J4"5;
"IOI4"
$PN"I4"19;
"IOH4"
$PN"H4"35;
"GNDG4"
$PN"G4"5;
"IOF4"
$PN"F4"18;
"IOE4"
$PN"E4"37;
"GNDD4"
$PN"D4"34;
"IOC4"
$PN"C4"33;
"GNDA4"
$PN"A4"40;
"GNDI3"
$PN"I3"31;
"IOH3"
$PN"H3"32;
"IOG3"
$PN"G3"42;
"GNDF3"
$PN"F3"5;
"IOE3"
$PN"E3"107;
"IOD3"
$PN"D3"105;
"GNDC3"
$PN"C3"5;
"IOA3"
$PN"A3"108;
"GNDJ2"
$PN"J2"5;
"IOF6"
$PN"F6"83;
"GNDG6"
$PN"G6"17;
"GNDJ8"
$PN"J8"17;
"IOI8"
$PN"I8"82;
"IOE6"
$PN"E6"81;
"GNDD6"
$PN"D6"17;
"IOC6"
$PN"C6"93;
"IOB6"
$PN"B6"94;
"GNDA6"
$PN"A6"92;
"IOB5"
$PN"B5"88;
"IOA5"
$PN"A5"87;
"GNDA2"
$PN"A2"5;
"GNDI1"
$PN"I1"5;
"IOH1"
$PN"H1"43;
"IOG1"
$PN"G1"48;
"IOB8"
$PN"B8"80;
"GNDA8"
$PN"A8"17;
"GNDI7"
$PN"I7"17;
"IOH8"
$PN"H8"79;
"IOF8"
$PN"F8"78;
"GNDG8"
$PN"G8"17;
"GNDD8"
$PN"D8"17;
"IOE8"
$PN"E8"23;
"IOC8"
$PN"C8"77;
"IOH7"
$PN"H7"85;
"IOG7"
$PN"G7"86;
"GNDF7"
$PN"F7"17;
"IOE7"
$PN"E7"76;
"IOD7"
$PN"D7"75;
"GNDC7"
$PN"C7"17;
"IOB7"
$PN"B7"84;
"IOA7"
$PN"A7"74;
"GNDJ6"
$PN"J6"17;
"IOI6"
$PN"I6"73;
"IOH6"
$PN"H6"72;
"IOE5"
$PN"E5"90;
"IOD5"
$PN"D5"89;
"GNDC5"
$PN"C5"17;
"IOB3"
$PN"B3"109;
"IOB4"
$PN"B4"21;
"IOA1"
$PN"A1"102;
"IOB1"
$PN"B1"101;
"GNDC1"
$PN"C1"5;
"IOD1"
$PN"D1"103;
"IOE1"
$PN"E1"100;
"GNDF1"
$PN"F1"5;
"IOC2"
$PN"C2"99;
"IOB2"
$PN"B2"104;
"IOE2"
$PN"E2"106;
"GNDD2"
$PN"D2"5;
"IOF2"
$PN"F2"112;
"GNDG2"
$PN"G2"5;
"IOH2"
$PN"H2"110;
"IOI2"
$PN"I2"111;
%"GND"
"1","(-1350,2425)","0","mstr_symbols","I112";
;
BOM_COST"NT_BASE_VRD"
ROOM"P2V5_LAN_AUX_VR"
BODY_TYPE"PLUMBING"
CDS_LIB"mstr_symbols"
VOLTAGE"0"
SIZE"1B"
HDL_POWER"GND";
"A\NAC"5;
%"TAP"
"1","(-1600,4450)","2","mstr_standard","I113";
;
HDL_TAP"TRUE"
CDS_LIB"mstr_standard"
BODY_TYPE"PLUMBING";
"B \NAC \NWC"1;
"S \NAC"
BN"2"48;
%"TAP"
"1","(-1850,4400)","2","mstr_standard","I114";
;
HDL_TAP"TRUE"
CDS_LIB"mstr_standard"
BODY_TYPE"PLUMBING";
"B \NAC \NWC"2;
"S \NAC"
BN"2"43;
%"TAP"
"1","(-1600,3900)","2","mstr_standard","I115";
;
HDL_TAP"TRUE"
CDS_LIB"mstr_standard"
BODY_TYPE"PLUMBING";
"B \NAC \NWC"1;
"S \NAC"
BN"5"110;
%"TAP"
"1","(-1850,3850)","2","mstr_standard","I116";
;
HDL_TAP"TRUE"
BODY_TYPE"PLUMBING"
CDS_LIB"mstr_standard";
"B \NAC \NWC"2;
"S \NAC"
BN"5"111;
%"TAP"
"6","(1700,3100)","2","mstr_standard","I117";
;
HDL_TAP"TRUE"
BODY_TYPE"PLUMBING"
CDS_LIB"mstr_standard";
"B \NAC \NWC"3;
"S \NAC"
BN"0"68;
%"TAP"
"6","(1950,3150)","2","mstr_standard","I118";
;
HDL_TAP"TRUE"
CDS_LIB"mstr_standard"
BODY_TYPE"PLUMBING";
"B \NAC \NWC"4;
"S \NAC"
BN"0"62;
%"TAP"
"6","(1700,2950)","2","mstr_standard","I119";
;
HDL_TAP"TRUE"
BODY_TYPE"PLUMBING"
CDS_LIB"mstr_standard";
"B \NAC \NWC"3;
"S \NAC"
BN"1"65;
%"TAP"
"6","(1950,3000)","2","mstr_standard","I120";
;
HDL_TAP"TRUE"
BODY_TYPE"PLUMBING"
CDS_LIB"mstr_standard";
"B \NAC \NWC"4;
"S \NAC"
BN"1"64;
%"TAP"
"6","(1950,2850)","2","mstr_standard","I121";
;
HDL_TAP"TRUE"
BODY_TYPE"PLUMBING"
CDS_LIB"mstr_standard";
"B \NAC \NWC"4;
"S \NAC"
BN"2"63;
%"TAP"
"6","(1700,2800)","2","mstr_standard","I122";
;
HDL_TAP"TRUE"
BODY_TYPE"PLUMBING"
CDS_LIB"mstr_standard";
"B \NAC \NWC"3;
"S \NAC"
BN"2"20;
%"TAP"
"6","(1950,3700)","2","mstr_standard","I123";
;
HDL_TAP"TRUE"
CDS_LIB"mstr_standard"
BODY_TYPE"PLUMBING";
"B \NAC \NWC"4;
"S \NAC"
BN"3"59;
%"TAP"
"6","(1700,3650)","2","mstr_standard","I124";
;
HDL_TAP"TRUE"
CDS_LIB"mstr_standard"
BODY_TYPE"PLUMBING";
"B \NAC \NWC"3;
"S \NAC"
BN"3"66;
%"TAP"
"6","(1950,3550)","2","mstr_standard","I125";
;
HDL_TAP"TRUE"
BODY_TYPE"PLUMBING"
CDS_LIB"mstr_standard";
"B \NAC \NWC"4;
"S \NAC"
BN"4"61;
%"TAP"
"6","(1700,3500)","2","mstr_standard","I126";
;
HDL_TAP"TRUE"
BODY_TYPE"PLUMBING"
CDS_LIB"mstr_standard";
"B \NAC \NWC"3;
"S \NAC"
BN"4"24;
%"TAP"
"6","(1950,3350)","2","mstr_standard","I127";
;
HDL_TAP"TRUE"
BODY_TYPE"PLUMBING"
CDS_LIB"mstr_standard";
"B \NAC \NWC"4;
"S \NAC"
BN"5"67;
%"TAP"
"6","(1700,3400)","2","mstr_standard","I128";
;
HDL_TAP"TRUE"
CDS_LIB"mstr_standard"
BODY_TYPE"PLUMBING";
"B \NAC \NWC"3;
"S \NAC"
BN"5"60;
%"TAP"
"6","(1950,4050)","2","mstr_standard","I129";
;
HDL_TAP"TRUE"
BODY_TYPE"PLUMBING"
CDS_LIB"mstr_standard";
"B \NAC \NWC"4;
"S \NAC"
BN"6"28;
%"TAP"
"6","(1700,4000)","2","mstr_standard","I130";
;
HDL_TAP"TRUE"
BODY_TYPE"PLUMBING"
CDS_LIB"mstr_standard";
"B \NAC \NWC"3;
"S \NAC"
BN"6"27;
%"TAP"
"6","(1950,3850)","2","mstr_standard","I131";
;
HDL_TAP"TRUE"
BODY_TYPE"PLUMBING"
CDS_LIB"mstr_standard";
"B \NAC \NWC"4;
"S \NAC"
BN"7"25;
%"TAP"
"6","(1700,3900)","2","mstr_standard","I132";
;
HDL_TAP"TRUE"
CDS_LIB"mstr_standard"
BODY_TYPE"PLUMBING";
"B \NAC \NWC"3;
"S \NAC"
BN"7"26;
%"CAP"
"2","(1025,4050)","0","mstr_discrete","I160";
;
CDS_SEC"1"
CDS_LIB"mstr_discrete"
CDS_LOCATION"C1F4"
BOM_COST"IO_SLOT"
ROOM"IO_SLOT"
SEC_TYPE"0402"
SEC"1"
VALUE"0.22UF"
VOLTAGE"16V"
MATERIAL"X7R"
TOLERANCE"10%"
PART_NUMBER"A36096-155"
LOCATION"C1F4"
PACK_TYPE"0402";
"A"
$PN"1"81;
"B"
$PN"2"28;
%"CAP"
"2","(600,4000)","0","mstr_discrete","I161";
;
CDS_SEC"1"
CDS_LIB"mstr_discrete"
ROOM"IO_SLOT"
BOM_COST"IO_SLOT"
SEC_TYPE"0402"
SEC"1"
CDS_LOCATION"C1F5"
PART_NUMBER"A36096-155"
VALUE"0.22UF"
VOLTAGE"16V"
MATERIAL"X7R"
TOLERANCE"10%"
PACK_TYPE"0402"
LOCATION"C1F5";
"A"
$PN"1"83;
"B"
$PN"2"27;
%"CAP"
"2","(1025,3900)","0","mstr_discrete","I162";
;
CDS_SEC"1"
CDS_LIB"mstr_discrete"
CDS_LOCATION"C1F2"
BOM_COST"IO_SLOT"
ROOM"IO_SLOT"
SEC_TYPE"0402"
SEC"1"
VALUE"0.22UF"
LOCATION"C1F2"
VOLTAGE"16V"
TOLERANCE"10%"
PACK_TYPE"0402"
PART_NUMBER"A36096-155"
MATERIAL"X7R";
"A"
$PN"1"72;
"B"
$PN"2"26;
%"CAP"
"2","(1025,3700)","0","mstr_discrete","I163";
;
CDS_SEC"1"
CDS_LIB"mstr_discrete"
CDS_LOCATION"C1F13"
ROOM"IO_SLOT"
BOM_COST"IO_SLOT"
SEC_TYPE"0402"
SEC"1"
VALUE"0.22UF"
LOCATION"C1F13"
VOLTAGE"16V"
MATERIAL"X7R"
TOLERANCE"10%"
PACK_TYPE"0402"
PART_NUMBER"A36096-155";
"A"
$PN"1"74;
"B"
$PN"2"59;
%"CAP"
"2","(1050,3550)","0","mstr_discrete","I164";
;
CDS_SEC"1"
CDS_LIB"mstr_discrete"
CDS_LOCATION"C1F10"
BOM_COST"IO_SLOT"
ROOM"IO_SLOT"
SEC"1"
SEC_TYPE"0402"
VALUE"0.22UF"
VOLTAGE"16V"
MATERIAL"X7R"
TOLERANCE"10%"
PART_NUMBER"A36096-155"
PACK_TYPE"0402"
LOCATION"C1F10";
"A"
$PN"1"75;
"B"
$PN"2"61;
%"CAP"
"2","(1050,3400)","0","mstr_discrete","I165";
;
CDS_SEC"1"
CDS_LIB"mstr_discrete"
CDS_LOCATION"C1F6"
BOM_COST"IO_SLOT"
ROOM"IO_SLOT"
SEC_TYPE"0402"
SEC"1"
VALUE"0.22UF"
LOCATION"C1F6"
VOLTAGE"16V"
PART_NUMBER"A36096-155"
MATERIAL"X7R"
TOLERANCE"10%"
PACK_TYPE"0402";
"A"
$PN"1"86;
"B"
$PN"2"60;
%"CAP"
"2","(1050,3150)","0","mstr_discrete","I166";
;
CDS_SEC"1"
CDS_LOCATION"C1F20"
CDS_LIB"mstr_discrete"
BOM_COST"IO_SLOT"
ROOM"IO_SLOT"
SEC_TYPE"0402"
SEC"1"
VALUE"0.22UF"
LOCATION"C1F20"
VOLTAGE"16V"
PART_NUMBER"A36096-155"
MATERIAL"X7R"
TOLERANCE"10%"
PACK_TYPE"0402";
"A"
$PN"1"80;
"B"
$PN"2"62;
%"CAP"
"2","(600,3850)","0","mstr_discrete","I167";
;
CDS_SEC"1"
CDS_LOCATION"C1F3"
BOM_COST"IO_SLOT"
CDS_LIB"mstr_discrete"
ROOM"IO_SLOT"
SEC_TYPE"0402"
SEC"1"
VALUE"0.22UF"
LOCATION"C1F3"
PART_NUMBER"A36096-155"
VOLTAGE"16V"
MATERIAL"X7R"
TOLERANCE"10%"
PACK_TYPE"0402";
"A"
$PN"1"73;
"B"
$PN"2"25;
%"CAP"
"2","(600,3650)","0","mstr_discrete","I168";
;
CDS_SEC"1"
CDS_LOCATION"C1F12"
CDS_LIB"mstr_discrete"
BOM_COST"IO_SLOT"
SEC"1"
SEC_TYPE"0402"
ROOM"IO_SLOT"
VALUE"0.22UF"
LOCATION"C1F12"
PART_NUMBER"A36096-155"
VOLTAGE"16V"
MATERIAL"X7R"
PACK_TYPE"0402"
TOLERANCE"10%";
"A"
$PN"1"84;
"B"
$PN"2"66;
%"CAP"
"2","(600,3500)","0","mstr_discrete","I169";
;
CDS_SEC"1"
CDS_LIB"mstr_discrete"
CDS_LOCATION"C1F11"
SEC"1"
BOM_COST"IO_SLOT"
SEC_TYPE"0402"
ROOM"IO_SLOT"
VALUE"0.22UF"
VOLTAGE"16V"
MATERIAL"X7R"
LOCATION"C1F11"
TOLERANCE"10%"
PACK_TYPE"0402"
PART_NUMBER"A36096-155";
"A"
$PN"1"76;
"B"
$PN"2"24;
%"CAP"
"2","(600,3350)","0","mstr_discrete","I170";
;
CDS_SEC"1"
CDS_LOCATION"C1F8"
BOM_COST"IO_SLOT"
CDS_LIB"mstr_discrete"
ROOM"IO_SLOT"
SEC_TYPE"0402"
SEC"1"
LOCATION"C1F8"
PART_NUMBER"A36096-155"
VOLTAGE"16V"
MATERIAL"X7R"
TOLERANCE"10%"
PACK_TYPE"0402"
VALUE"0.22UF";
"A"
$PN"1"85;
"B"
$PN"2"67;
%"CAP"
"2","(550,3100)","0","mstr_discrete","I171";
;
CDS_SEC"1"
BOM_COST"IO_SLOT"
CDS_LIB"mstr_discrete"
CDS_LOCATION"C1F18"
ROOM"IO_SLOT"
SEC"1"
SEC_TYPE"0402"
VALUE"0.22UF"
LOCATION"C1F18"
VOLTAGE"16V"
PART_NUMBER"A36096-155"
TOLERANCE"10%"
MATERIAL"X7R"
PACK_TYPE"0402";
"A"
$PN"1"77;
"B"
$PN"2"68;
%"CAP"
"2","(1050,3000)","0","mstr_discrete","I172";
;
CDS_SEC"1"
CDS_LIB"mstr_discrete"
CDS_LOCATION"C1F16"
SEC"1"
SEC_TYPE"0402"
BOM_COST"IO_SLOT"
ROOM"IO_SLOT"
VALUE"0.22UF"
LOCATION"C1F16"
VOLTAGE"16V"
PART_NUMBER"A36096-155"
MATERIAL"X7R"
TOLERANCE"10%"
PACK_TYPE"0402";
"A"
$PN"1"23;
"B"
$PN"2"64;
%"CAP"
"2","(550,2950)","0","mstr_discrete","I173";
;
CDS_SEC"1"
CDS_LIB"mstr_discrete"
CDS_LOCATION"C1F17"
ROOM"IO_SLOT"
SEC"1"
SEC_TYPE"0402"
BOM_COST"IO_SLOT"
MATERIAL"X7R"
VALUE"0.22UF"
LOCATION"C1F17"
VOLTAGE"16V"
PART_NUMBER"A36096-155"
TOLERANCE"10%"
PACK_TYPE"0402";
"A"
$PN"1"78;
"B"
$PN"2"65;
%"CAP"
"2","(1050,2850)","0","mstr_discrete","I174";
;
CDS_SEC"1"
CDS_LOCATION"C1F15"
BOM_COST"IO_SLOT"
CDS_LIB"mstr_discrete"
ROOM"IO_SLOT"
SEC"1"
SEC_TYPE"0402"
VOLTAGE"16V"
VALUE"0.22UF"
LOCATION"C1F15"
MATERIAL"X7R"
PART_NUMBER"A36096-155"
TOLERANCE"10%"
PACK_TYPE"0402";
"A"
$PN"1"79;
"B"
$PN"2"63;
%"CAP"
"2","(550,2800)","0","mstr_discrete","I175";
;
CDS_SEC"1"
CDS_LIB"mstr_discrete"
CDS_LOCATION"C1F14"
BOM_COST"IO_SLOT"
ROOM"IO_SLOT"
SEC_TYPE"0402"
SEC"1"
VALUE"0.22UF"
LOCATION"C1F14"
VOLTAGE"16V"
PART_NUMBER"A36096-155"
TOLERANCE"10%"
MATERIAL"X7R"
PACK_TYPE"0402";
"A"
$PN"1"82;
"B"
$PN"2"20;
%"P12V_PSU"
"1","(-2600,2325)","0","mstr_symbols","I176";
;
VOLTAGE"12.0"
BODY_TYPE"PLUMBING"
HDL_POWER"P12V_PSU"
ROOM"P2V5_LAN_AUX_VR"
BOM_COST"NT_BASE_VRD"
CDS_LIB"mstr_symbols";
"G\NAC"6;
%"RES"
"2","(-2600,2100)","0","mstr_discrete","I177";
;
CDS_SEC"1"
CDS_LIB"mstr_discrete"
ROOM"IO_SLOT"
BOM_COST"IO_SLOT"
SEC_TYPE"0402"
SEC"1"
CDS_LOCATION"R9T9"
LOCATION"R9T9"
WATTAGE"1/16W"
VALUE"4.75K"
TOLERANCE"1%"
MATERIAL"CHIP"
PART_NUMBER"G21796-072"
PACK_TYPE"0402";
"A"
$PN"1"6;
"B"
$PN"2"29;
%"DIODE"
"1","(-2275,1800)","0","mstr_discrete","I178";
;
CDS_SEC"1"
CDS_LOCATION"CR1F4"
CDS_LIB"mstr_discrete"
ROOM"IO_SLOT"
BOM_COST"IO_SLOT"
SEC_TYPE"SM"
SEC"1"
LOCATION"CR1F4"
PART_NUMBER"H71799-001"
MATERIAL"IC"
PACK_TYPE"SM"
VALUE"SDMK0340L";
"C"
$PN"1"30;
"A"
$PN"2"29;
%"DIODE"
"1","(-1025,1800)","0","mstr_discrete","I180";
;
CDS_SEC"1"
CDS_LIB"mstr_discrete"
CDS_LOCATION"CR1F3"
SEC"1"
BOM_COST"IO_SLOT"
SEC_TYPE"SM"
ROOM"IO_SLOT"
LOCATION"CR1F3"
PART_NUMBER"H71799-001"
VALUE"SDMK0340L"
MATERIAL"IC"
PACK_TYPE"SM";
"C"
$PN"1"113;
"A"
$PN"2"30;
%"NPN"
"1","(50,1800)","0","mstr_discrete","I181";
;
CDS_SEC"1"
CDS_LIB"mstr_discrete"
CDS_LOCATION"Q9T1"
SEC"1"
SEC_TYPE"SM"
ROOM"SB"
LOCATION"Q9T1"
PART_NUMBER"C52245-001"
VALUE"MMBT3904"
PACK_TYPE"SM"
MATERIAL"IC";
"C"
$PN"3"69;
"E"
$PN"2"7;
"B"
$PN"1"113;
%"GND"
"1","(100,1525)","0","mstr_symbols","I182";
;
BOM_COST"NT_BASE_VRD"
ROOM"P2V5_LAN_AUX_VR"
SIZE"1B"
BODY_TYPE"PLUMBING"
VOLTAGE"0"
CDS_LIB"mstr_symbols"
HDL_POWER"GND";
"A\NAC"7;
%"RES"
"2","(450,2150)","2","mstr_discrete","I183";
;
CDS_SEC"1"
CDS_LIB"mstr_discrete"
CDS_LOCATION"R9T6"
ROOM"IO_SLOT"
SEC_TYPE"0402"
BOM_COST"IO_SLOT"
SEC"1"
PART_NUMBER"G21796-107"
MATERIAL"CHIP"
PACK_TYPE"0402"
TOLERANCE"1%"
VALUE"15.0K"
LOCATION"R9T6"
WATTAGE"1/16W";
"A"
$PN"1"8;
"B"
$PN"2"69;
%"P12V_PSU"
"1","(450,2350)","0","mstr_symbols","I184";
;
VOLTAGE"12.0"
HDL_POWER"P12V_PSU"
ROOM"P2V5_LAN_AUX_VR"
BOM_COST"NT_BASE_VRD"
CDS_LIB"mstr_symbols"
BODY_TYPE"PLUMBING";
"G\NAC"8;
%"RES"
"2","(550,1800)","0","mstr_discrete","I185";
;
CDS_SEC"1"
CDS_LIB"mstr_discrete"
CDS_LOCATION"R9T3"
ROOM"IO_SLOT"
SEC_TYPE"0402"
SEC"1"
BOM_COST"IO_SLOT"
PACK_TYPE"0402"
MATERIAL"CHIP"
WATTAGE"1/16W"
TOLERANCE"1%"
VALUE"6.19K"
LOCATION"R9T3"
PART_NUMBER"G21796-161";
"A"
$PN"1"69;
"B"
$PN"2"9;
%"GND"
"1","(550,1500)","0","mstr_symbols","I186";
;
BODY_TYPE"PLUMBING"
BOM_COST"NT_BASE_VRD"
ROOM"P2V5_LAN_AUX_VR"
SIZE"1B"
VOLTAGE"0"
CDS_LIB"mstr_symbols"
HDL_POWER"GND";
"A\NAC"9;
%"CONN8_H62179001"
"1","(3500,1500)","0","mstr_conn","I189";
;
CDS_LIB"mstr_conn"
CDS_SEC"1"
$SEC"1"
CDS_LOCATION"J1F3"
ROOM"IO_SLOT"
PACK_TYPE"PIP"
MATERIAL"CONN"
LOCATION"J1F3"
PART_NUMBER"H62179-001";
"IO1"
$PN"1"13;
"IO3"
$PN"3"57;
"IO2"
$PN"2"58;
"IO4"
$PN"4"53;
"IO6"
$PN"6"56;
"IO5"
$PN"5"54;
"IO8"
$PN"8"10;
"IO7"
$PN"7"55;
%"GND"
"1","(3050,1050)","0","mstr_symbols","I191";
;
BODY_TYPE"PLUMBING"
BOM_COST"NT_BASE_VRD"
ROOM"P2V5_LAN_AUX_VR"
CDS_LIB"mstr_symbols"
HDL_POWER"GND"
VOLTAGE"0"
SIZE"1B";
"A\NAC"10;
%"P3V3_STBY"
"1","(1725,2625)","0","mstr_symbols","I198";
;
HDL_POWER"P3V3_STBY"
CDS_LIB"mstr_symbols"
SIZE"1B"
BODY_TYPE"PLUMBING"
VOLTAGE"3.3V";
"G\NAC"11;
%"RES"
"1","(2050,2475)","0","mstr_discrete","I199";
;
CDS_SEC"1"
CDS_LOCATION"R7D5"
SEC"1"
SEC_TYPE"0402"
ROOM"IO_SLOT"
CDS_LIB"mstr_discrete"
PACK_TYPE"0402"
WATTAGE"1/16W"
VALUE"2.26K"
LOCATION"R7D5"
TOLERANCE"1.0%"
MATERIAL"CHIP"
PART_NUMBER"G21796-311";
"B"
$PN"2"52;
"A"
$PN"1"11;
%"RES"
"1","(2050,2300)","0","mstr_discrete","I200";
;
CDS_SEC"1"
CDS_LOCATION"R7D9"
SEC"1"
SEC_TYPE"0402"
ROOM"IO_SLOT"
CDS_LIB"mstr_discrete"
PACK_TYPE"0402"
VALUE"2.26K"
WATTAGE"1/16W"
LOCATION"R7D9"
TOLERANCE"1.0%"
MATERIAL"CHIP"
PART_NUMBER"G21796-311";
"B"
$PN"2"51;
"A"
$PN"1"11;
%"RES"
"1","(2050,2125)","0","mstr_discrete","I201";
;
CDS_SEC"1"
CDS_LOCATION"R3P61"
ROOM"IO_SLOT"
SEC_TYPE"0402"
SEC"1"
CDS_LIB"mstr_discrete"
PACK_TYPE"0402"
WATTAGE"1/16W"
VALUE"2.26K"
LOCATION"R3P61"
TOLERANCE"1.0%"
MATERIAL"CHIP"
PART_NUMBER"G21796-311";
"B"
$PN"2"50;
"A"
$PN"1"11;
%"RES"
"1","(1050,1075)","0","mstr_discrete","I218";
;
CDS_SEC"1"
ROOM"IO_SLOT"
SEC_TYPE"0402"
SEC"1"
CDS_LOCATION"R8E5"
CDS_LIB"mstr_discrete"
LOCATION"R8E5"
PART_NUMBER"G21796-074"
VALUE"33.2"
WATTAGE"1/16W"
TOLERANCE"1%"
PACK_TYPE"0402"
MATERIAL"CHIP";
"B"
$PN"2"70;
"A"
$PN"1"71;
%"CAP"
"1","(-300,875)","0","mstr_discrete","I224";
;
CDS_SEC"1"
CDS_LOCATION"C2R6"
CDS_LIB"mstr_discrete"
SEC"1"
SEC_TYPE"0402LF"
ROOM"IO_SLOT"
PACK_TYPE"0402LF"
TOLERANCE"10%"
VOLTAGE"50V"
MATERIAL"EMPTY"
VALUE"470PF"
PART_NUMBER"A36096-049"
LOCATION"C2R6";
"A"
$PN"1"49;
"B"
$PN"2"12;
%"GND"
"1","(-300,700)","0","mstr_symbols","I225";
;
ROOM"P2V5_LAN_AUX_VR"
BOM_COST"NT_BASE_VRD"
VOLTAGE"0"
CDS_LIB"mstr_symbols"
BODY_TYPE"PLUMBING"
HDL_POWER"GND"
SIZE"1B";
"A\NAC"12;
%"P3V3_STBY"
"1","(3050,1850)","0","mstr_symbols","I227";
;
CDS_LIB"mstr_symbols"
BODY_TYPE"PLUMBING"
HDL_POWER"P3V3_STBY"
VOLTAGE"3.3V"
SIZE"1B";
"G\NAC"13;
%"TTL08"
"1","(250,1075)","0","mstr_ttl","I243";
;
CDS_SEC"2"
CDS_LIB"mstr_ttl"
SEC"2"
BOM_COST"FAST_PROCHOT"
SEC_TYPE"QFN15"
CDS_LOCATION"U8E1"
ROOM"FAST_PROCHOT"
PACK_TYPE"QFN15"
POWER_GROUP"VCC=P3V3_STBY;GND=GND;TH=GND"
PART_NUMBER"D90404-001"
MATERIAL"IC"
LOCATION"U8E1"
VALUE"74LVC08A";
"A <SIZE-1..0>"
$PN"9"49;
"B <SIZE-1..0>"
$PN"10"95;
"Y <SIZE-1..0>"
$PN"8"71;
%"GND"
"1","(-3000,1175)","0","mstr_symbols","I248";
;
VOLTAGE"0.0V"
CDS_LIB"mstr_symbols"
SIZE"1B"
BODY_TYPE"PLUMBING"
HDL_POWER"GND";
"A\NAC"14;
%"P3V3_STBY"
"1","(-1525,1325)","0","mstr_symbols","I251";
;
VOLTAGE"3.3V"
HDL_POWER"P3V3_STBY"
BODY_TYPE"PLUMBING"
CDS_LIB"mstr_symbols"
SIZE"1B";
"G\NAC"15;
%"GND"
"1","(-1525,725)","0","mstr_symbols","I252";
;
VOLTAGE"0.0V"
BODY_TYPE"PLUMBING"
CDS_LIB"mstr_symbols"
SIZE"1B"
HDL_POWER"GND";
"A\NAC"16;
%"CAP_A"
"1","(-1525,1025)","0","dev_discrete","I253";
;
CDS_LOCATION"C8E1"
CDS_LIB"dev_discrete"
BOM_COST"IO_SLOT"
CDS_SEC"1"
SEC_TYPE"0402V"
SEC"1"
ROOM"IO_SLOT"
TOLERANCE"10%"
PACK_TYPE"0402V"
MATERIAL"X7R"
PART_NUMBER"A36096-030"
VOLTAGE"16V"
VALUE"0.1UF"
LOCATION"C8E1";
"B"
$PN"2"16;
"A"
$PN"1"15;
%"RES"
"1","(-2125,3200)","0","mstr_discrete","I254";
;
CDS_SEC"1"
CDS_LIB"mstr_discrete"
CDS_LOCATION"R9R9"
SEC_TYPE"0402"
SEC"1"
WATTAGE"1/16W"
VALUE"0.0"
MATERIAL"CHIP"
PACK_TYPE"0402"
LOCATION"R9R9"
TOLERANCE"5%"
PART_NUMBER"G21497-005";
"B"
$PN"2"40;
"A"
$PN"1"22;
%"RES"
"1","(-2825,3150)","0","mstr_discrete","I255";
;
CDS_SEC"1"
CDS_LIB"mstr_discrete"
CDS_LOCATION"R9R12"
SEC"1"
SEC_TYPE"0402"
PACK_TYPE"0402"
MATERIAL"CHIP"
TOLERANCE"5%"
VALUE"0.0"
WATTAGE"1/16W"
PART_NUMBER"G21497-005"
LOCATION"R9R12";
"B"
$PN"2"21;
"A"
$PN"1"47;
%"RES"
"1","(-2125,3100)","0","mstr_discrete","I256";
;
CDS_SEC"1"
CDS_LIB"mstr_discrete"
CDS_LOCATION"R9R10"
SEC_TYPE"0402"
SEC"1"
MATERIAL"CHIP"
WATTAGE"1/16W"
VALUE"0.0"
LOCATION"R9R10"
PART_NUMBER"G21497-005"
PACK_TYPE"0402"
TOLERANCE"5%";
"B"
$PN"2"33;
"A"
$PN"1"41;
%"RES"
"1","(-2100,2950)","0","mstr_discrete","I261";
;
CDS_SEC"1"
SEC"1"
SEC_TYPE"0402"
CDS_LIB"mstr_discrete"
CDS_LOCATION"R9T1"
PART_NUMBER"G21497-005"
PACK_TYPE"0402"
MATERIAL"CHIP"
TOLERANCE"5%"
LOCATION"R9T1"
VALUE"0.0"
WATTAGE"1/16W";
"B"
$PN"2"18;
"A"
$PN"1"36;
%"RES"
"1","(-2825,3050)","0","mstr_discrete","I268";
;
CDS_SEC"1"
CDS_LOCATION"R1F8"
WATTAGE"1/16W"
TOLERANCE"5%"
MATERIAL"CHIP"
PACK_TYPE"0402"
CDS_LIB"mstr_discrete"
SEC_TYPE"0402"
SEC"1"
VALUE"0.0"
PART_NUMBER"G21497-005"
LOCATION"R1F8";
"B"
$PN"2"34;
"A"
$PN"1"39;
%"RES"
"1","(-3000,1475)","1","mstr_discrete","I278";
;
CDS_SEC"1"
$SEC"1"
CDS_LOCATION"R9T8"
MATERIAL"CHIP"
CDS_LIB"mstr_discrete"
VALUE"0.0"
WATTAGE"1/16W"
TOLERANCE"5%"
PACK_TYPE"0402"
PART_NUMBER"G21497-005"
LOCATION"R9T8";
"B"
$PN"2"29;
"A"
$PN"1"14;
%"RES"
"1","(-2375,3850)","0","mstr_discrete","I279";
;
CDS_LOCATION"R9F67"
ROOM"UART_MUX"
PACK_TYPE"0402"
CDS_LIB"mstr_discrete"
$SEC"1"
CDS_SEC"1"
PART_NUMBER"G21497-005"
TOLERANCE"5%"
LOCATION"R9F67"
VALUE"0.0"
WATTAGE"1/16W"
MATERIAL"CHIP";
"B"
$PN"2"42;
"A"
$PN"1"46;
%"RES"
"1","(-2350,3400)","0","mstr_discrete","I280";
;
CDS_LOCATION"R9F70"
CDS_SEC"1"
CDS_LIB"mstr_discrete"
SEC"1"
SEC_TYPE"0402"
ROOM"UART_MUX"
PACK_TYPE"0402"
TOLERANCE"5%"
PART_NUMBER"G21497-005"
VALUE"0.0"
MATERIAL"EMPTY"
LOCATION"R9F70"
WATTAGE"1/16W";
"B"
$PN"2"42;
"A"
$PN"1"44;
%"RES"
"1","(-2775,3800)","0","mstr_discrete","I281";
;
CDS_LOCATION"R9F64"
PACK_TYPE"0402"
SEC_TYPE"0402"
ROOM"UART_MUX"
WATTAGE"1/16W"
CDS_LIB"mstr_discrete"
TOLERANCE"5%"
SEC"1"
CDS_SEC"1"
PART_NUMBER"G21497-005"
MATERIAL"CHIP"
VALUE"0.0"
LOCATION"R9F64";
"B"
$PN"2"32;
"A"
$PN"1"38;
%"RES"
"1","(-2725,3350)","0","mstr_discrete","I282";
;
CDS_LOCATION"R9F63"
CDS_SEC"1"
TOLERANCE"5%"
WATTAGE"1/16W"
ROOM"UART_MUX"
SEC_TYPE"0402"
SEC"1"
CDS_LIB"mstr_discrete"
PACK_TYPE"0402"
PART_NUMBER"G21497-005"
LOCATION"R9F63"
MATERIAL"EMPTY"
VALUE"0.0";
"B"
$PN"2"32;
"A"
$PN"1"45;
%"GND"
"1","(50,2375)","0","mstr_symbols","I45";
;
ROOM"P2V5_LAN_AUX_VR"
BOM_COST"NT_BASE_VRD"
VOLTAGE"0"
SIZE"1B"
CDS_LIB"mstr_symbols"
BODY_TYPE"PLUMBING"
HDL_POWER"GND";
"A\NAC"17;
%"TAP"
"1","(-1600,4700)","2","mstr_standard","I47";
;
HDL_TAP"TRUE"
BODY_TYPE"PLUMBING"
CDS_LIB"mstr_standard";
"B \NAC \NWC"1;
"S \NAC"
BN"0"101;
%"TAP"
"1","(-1600,4550)","2","mstr_standard","I48";
;
HDL_TAP"TRUE"
CDS_LIB"mstr_standard"
BODY_TYPE"PLUMBING";
"B \NAC \NWC"1;
"S \NAC"
BN"1"100;
%"TAP"
"1","(-1850,4750)","2","mstr_standard","I49";
;
HDL_TAP"TRUE"
BODY_TYPE"PLUMBING"
CDS_LIB"mstr_standard";
"B \NAC \NWC"2;
"S \NAC"
BN"0"102;
%"TAP"
"1","(-1850,4600)","2","mstr_standard","I50";
;
HDL_TAP"TRUE"
CDS_LIB"mstr_standard"
BODY_TYPE"PLUMBING";
"B \NAC \NWC"2;
"S \NAC"
BN"1"103;
%"TAP"
"1","(-1600,4150)","2","mstr_standard","I53";
;
HDL_TAP"TRUE"
CDS_LIB"mstr_standard"
BODY_TYPE"PLUMBING";
"B \NAC \NWC"1;
"S \NAC"
BN"3"99;
%"TAP"
"1","(-1600,4000)","2","mstr_standard","I54";
;
HDL_TAP"TRUE"
CDS_LIB"mstr_standard"
BODY_TYPE"PLUMBING";
"B \NAC \NWC"1;
"S \NAC"
BN"4"112;
%"TAP"
"1","(-1850,4200)","2","mstr_standard","I57";
;
HDL_TAP"TRUE"
BODY_TYPE"PLUMBING"
CDS_LIB"mstr_standard";
"B \NAC \NWC"2;
"S \NAC"
BN"3"104;
%"TAP"
"1","(-1850,4050)","2","mstr_standard","I58";
;
HDL_TAP"TRUE"
CDS_LIB"mstr_standard"
BODY_TYPE"PLUMBING";
"B \NAC \NWC"2;
"S \NAC"
BN"4"106;
%"TAP"
"1","(-1600,3700)","2","mstr_standard","I67";
;
HDL_TAP"TRUE"
CDS_LIB"mstr_standard"
BODY_TYPE"PLUMBING";
"B \NAC \NWC"1;
"S \NAC"
BN"6"108;
%"TAP"
"1","(-1600,3500)","2","mstr_standard","I68";
;
HDL_TAP"TRUE"
CDS_LIB"mstr_standard"
BODY_TYPE"PLUMBING";
"B \NAC \NWC"1;
"S \NAC"
BN"7"107;
%"TAP"
"1","(-1850,3550)","2","mstr_standard","I69";
;
HDL_TAP"TRUE"
CDS_LIB"mstr_standard"
BODY_TYPE"PLUMBING";
"B \NAC \NWC"2;
"S \NAC"
BN"7"105;
%"TAP"
"1","(-1850,3650)","2","mstr_standard","I70";
;
HDL_TAP"TRUE"
CDS_LIB"mstr_standard"
BODY_TYPE"PLUMBING";
"B \NAC \NWC"2;
"S \NAC"
BN"6"109;
END.
